FILE_TYPE=LIBRARY_PARTS;
primitive '9ZXL0451EKILFT';
  pin
    'DIF_IN':
      PIN_NUMBER='(3)';
      INPUT_LOAD='(-0.01,0.01)';
    'DIF_IN#':
      PIN_NUMBER='(4)';
      INPUT_LOAD='(-0.01,0.01)';
    'VDDR':
      PIN_NUMBER='(2)';
      PINUSE='POWER';
      NO_LOAD_CHECK='Both';
      NO_IO_CHECK='Both';
      NO_ASSERT_CHECK='TRUE';
      NO_DIR_CHECK='TRUE';
      ALLOW_CONNECT='TRUE';
    'VDD3':
      PIN_NUMBER='(25)';
      PINUSE='POWER';
      NO_LOAD_CHECK='Both';
      NO_IO_CHECK='Both';
      NO_ASSERT_CHECK='TRUE';
      NO_DIR_CHECK='TRUE';
      ALLOW_CONNECT='TRUE';
    'VDD4':
      PIN_NUMBER='(29)';
      PINUSE='POWER';
      NO_LOAD_CHECK='Both';
      NO_IO_CHECK='Both';
      NO_ASSERT_CHECK='TRUE';
      NO_DIR_CHECK='TRUE';
      ALLOW_CONNECT='TRUE';
    'FBOUT_NC':
      PIN_NUMBER='(9)';
      OUTPUT_LOAD='(1.0,-1.0)';
    'VOE0#':
      PIN_NUMBER='(15)';
      INPUT_LOAD='(-0.01,0.01)';
    'VOE3#':
      PIN_NUMBER='(26)';
      INPUT_LOAD='(-0.01,0.01)';
    'SMBDAT':
      PIN_NUMBER='(6)';
      BIDIRECTIONAL='TRUE';
      INPUT_LOAD='(-0.01,0.01)';
      OUTPUT_LOAD='(1.0,-1.0)';
    'NC1':
      PIN_NUMBER='(11)';
      OUTPUT_TYPE='(TS,TS)';
      INPUT_LOAD='(-0.01,0.01)';
      OUTPUT_LOAD='(1.0,-1.0)';
    'FBOUT_NC#':
      PIN_NUMBER='(8)';
      OUTPUT_LOAD='(1.0,-1.0)';
    'SMBCLK':
      PIN_NUMBER='(7)';
      INPUT_LOAD='(-0.01,0.01)';
    'VDD2':
      PIN_NUMBER='(21)';
      PINUSE='POWER';
      NO_LOAD_CHECK='Both';
      NO_IO_CHECK='Both';
      NO_ASSERT_CHECK='TRUE';
      NO_DIR_CHECK='TRUE';
      ALLOW_CONNECT='TRUE';
    '^CKPWRGD_PD#':
      PIN_NUMBER='(1)';
      INPUT_LOAD='(-0.01,0.01)';
    'DIF0#':
      PIN_NUMBER='(14)';
      OUTPUT_LOAD='(1.0,-1.0)';
    'DIF0':
      PIN_NUMBER='(13)';
      OUTPUT_LOAD='(1.0,-1.0)';
    'VOE1#':
      PIN_NUMBER='(18)';
      INPUT_LOAD='(-0.01,0.01)';
    'DIF1#':
      PIN_NUMBER='(20)';
      OUTPUT_LOAD='(1.0,-1.0)';
    'DIF2':
      PIN_NUMBER='(22)';
      OUTPUT_LOAD='(1.0,-1.0)';
    'VOE2#':
      PIN_NUMBER='(24)';
      INPUT_LOAD='(-0.01,0.01)';
    'DIF2#':
      PIN_NUMBER='(23)';
      OUTPUT_LOAD='(1.0,-1.0)';
    'DIF3#':
      PIN_NUMBER='(28)';
      OUTPUT_LOAD='(1.0,-1.0)';
    'NC0':
      PIN_NUMBER='(10)';
      OUTPUT_TYPE='(TS,TS)';
      INPUT_LOAD='(-0.01,0.01)';
      OUTPUT_LOAD='(1.0,-1.0)';
    'VDDA':
      PIN_NUMBER='(31)';
      PINUSE='POWER';
      NO_LOAD_CHECK='Both';
      NO_IO_CHECK='Both';
      NO_ASSERT_CHECK='TRUE';
      NO_DIR_CHECK='TRUE';
      ALLOW_CONNECT='TRUE';
    'VDD1':
      PIN_NUMBER='(16)';
      PINUSE='POWER';
      NO_LOAD_CHECK='Both';
      NO_IO_CHECK='Both';
      NO_ASSERT_CHECK='TRUE';
      NO_DIR_CHECK='TRUE';
      ALLOW_CONNECT='TRUE';
    '^HIBW_BYPM_LOBW#':
      PIN_NUMBER='(32)';
      INPUT_LOAD='(-0.01,0.01)';
    'EPAD_GND':
      PIN_NUMBER='(33)';
      PINUSE='POWER';
      NO_LOAD_CHECK='Both';
      NO_IO_CHECK='Both';
      NO_ASSERT_CHECK='TRUE';
      NO_DIR_CHECK='TRUE';
      ALLOW_CONNECT='TRUE';
    'DIF1':
      PIN_NUMBER='(19)';
      OUTPUT_LOAD='(1.0,-1.0)';
    'DIF3':
      PIN_NUMBER='(27)';
      OUTPUT_LOAD='(1.0,-1.0)';
    'VDD0':
      PIN_NUMBER='(12)';
      PINUSE='POWER';
      NO_LOAD_CHECK='Both';
      NO_IO_CHECK='Both';
      NO_ASSERT_CHECK='TRUE';
      NO_DIR_CHECK='TRUE';
      ALLOW_CONNECT='TRUE';
    'NC3':
      PIN_NUMBER='(30)';
      OUTPUT_TYPE='(TS,TS)';
      INPUT_LOAD='(-0.01,0.01)';
      OUTPUT_LOAD='(1.0,-1.0)';
    'NC2':
      PIN_NUMBER='(17)';
      OUTPUT_TYPE='(TS,TS)';
      INPUT_LOAD='(-0.01,0.01)';
      OUTPUT_LOAD='(1.0,-1.0)';
    'VSADR0_TRI':
      PIN_NUMBER='(5)';
      INPUT_LOAD='(-0.01,0.01)';
  end_pin;
  body
    PART_NAME='9ZXL0451EKILFT';
    BODY_NAME='9ZXL0451EKILFT';
    PHYS_DES_PREFIX='U';
    CLASS='IC';
  end_body;
end_primitive;

END.
